(kicad_pcb
	(version 20260206)
	(generator "pcbnew")
	(generator_version "10.0")
	(general
		(thickness 1.6)
		(legacy_teardrops no)
	)
	(paper "A4")
	(title_block
		(title "Wiwynn_Tioga_Pass_MB.brd")
		(comment 1 "Tioga Pass / footprints 3270-3277 of 4770")
	)
	(layers
		(0 "F.Cu" signal "TOP")
		(4 "In1.Cu" signal "L2GND")
		(6 "In2.Cu" signal "L3")
		(8 "In3.Cu" signal "L4GND")
		(10 "In4.Cu" signal "L5")
		(12 "In5.Cu" signal "L6GND")
		(14 "In6.Cu" signal "L7VCC")
		(16 "In7.Cu" signal "L8VCC")
		(18 "In8.Cu" signal "L9GND")
		(20 "In9.Cu" signal "L10")
		(22 "In10.Cu" signal "L11GND")
		(24 "In11.Cu" signal "L12")
		(26 "In12.Cu" signal "L13GND")
		(2 "B.Cu" signal "BOTTOM")
		(9 "F.Adhes" user "F.Adhesive")
		(11 "B.Adhes" user "B.Adhesive")
		(13 "F.Paste" user "Package Geometry/Pastemask Top")
		(15 "B.Paste" user "Package Geometry/Pastemask Bottom")
		(5 "F.SilkS" user "Ref Des/Silkscreen Top")
		(7 "B.SilkS" user "Ref Des/Silkscreen Bottom")
		(1 "F.Mask" user "Board Geometry/Soldermask Top")
		(3 "B.Mask" user "Board Geometry/Soldermask Bottom")
		(17 "Dwgs.User" user "User.Drawings")
		(19 "Cmts.User" user "User.Comments")
		(21 "Eco1.User" user "User.Eco1")
		(23 "Eco2.User" user "User.Eco2")
		(25 "Edge.Cuts" user "Board Geometry/Outline")
		(27 "Margin" user)
		(31 "F.CrtYd" user "Package Geometry/Place Bound Top")
		(29 "B.CrtYd" user "Package Geometry/Place Bound Bottom")
		(35 "F.Fab" user "Ref Des/Assembly Top")
		(33 "B.Fab" user "Ref Des/Assembly Bottom")
	)
	(footprint ""
		(layer "B.Cu")
		(at 414.75152 -45.576744 -90)
		(property "Reference" "C25W40"
			(at 0.8382 -0.67818 270)
			(unlocked yes)
			(layer "B.SilkS")
			(effects
				(font
					(size 0.4064 0.254)
					(thickness 0.1524)
				)
				(justify left mirror)
			)
		)
		(property "Value" ""
			(at 0 0 90)
			(layer "B.Fab")
			(effects
				(font
					(size 1.27 1.27)
				)
				(justify mirror)
			)
		)
		(duplicate_pad_numbers_are_jumpers no)
		(fp_poly
			(pts
				(xy -0.3048 -0.1016) (xy -0.3048 0.9906) (xy 0.3048 0.9906) (xy 0.3048 -0.1016)
			)
			(stroke
				(width 0)
				(type default)
			)
			(fill no)
			(layer "B.CrtYd")
		)
		(fp_line
			(start -0.3048 0.9906)
			(end -0.3048 -0.1016)
			(stroke
				(width 0.1)
				(type default)
			)
			(layer "B.Fab")
		)
		(fp_line
			(start 0.3048 0.9906)
			(end -0.3048 0.9906)
			(stroke
				(width 0.1)
				(type default)
			)
			(layer "B.Fab")
		)
		(fp_line
			(start -0.3048 -0.1016)
			(end 0.3048 -0.1016)
			(stroke
				(width 0.1)
				(type default)
			)
			(layer "B.Fab")
		)
		(fp_line
			(start 0.3048 -0.1016)
			(end 0.3048 0.9906)
			(stroke
				(width 0.1)
				(type default)
			)
			(layer "B.Fab")
		)
		(pad "1" smd rect
			(at 0 0 90)
			(size 0.508 0.508)
			(layers "B.Cu" "B.Mask" "B.Paste")
			(net "VCC_D_3V3")
		)
		(pad "2" smd rect
			(at 0 0.889 90)
			(size 0.508 0.508)
			(layers "B.Cu" "B.Mask" "B.Paste")
			(net "GND")
		)
		(zone
			(layer "B.Cu")
			(hatch none 0.5)
			(connect_pads
				(clearance 0)
			)
			(min_thickness 0.25)
			(keepout
				(tracks not_allowed)
				(vias allowed)
				(pads allowed)
				(copperpour not_allowed)
				(footprints allowed)
			)
			(placement
				(enabled no)
				(sheetname "")
			)
			(fill
				(thermal_gap 0.5)
				(thermal_bridge_width 0.5)
				(island_removal_mode 0)
			)
			(polygon
				(pts
					(xy 414.11652 -45.322744) (xy 414.11652 -45.830744) (xy 414.49752 -45.830744) (xy 414.49752 -45.322744)
				)
			)
		)
		(zone
			(layer "B.Cu")
			(hatch none 0.5)
			(connect_pads
				(clearance 0)
			)
			(min_thickness 0.25)
			(keepout
				(tracks allowed)
				(vias not_allowed)
				(pads allowed)
				(copperpour not_allowed)
				(footprints allowed)
			)
			(placement
				(enabled no)
				(sheetname "")
			)
			(fill
				(thermal_gap 0.5)
				(thermal_bridge_width 0.5)
				(island_removal_mode 0)
			)
			(polygon
				(pts
					(xy 414.49752 -45.322744) (xy 414.49752 -45.830744) (xy 414.11652 -45.830744) (xy 414.11652 -45.322744)
				)
			)
		)
	)
	(footprint ""
		(layer "B.Cu")
		(at 351.2312 -85.9536 90)
		(property "Reference" "C3P2"
			(at 0 0 90)
			(layer "B.SilkS")
			(hide yes)
			(effects
				(font
					(size 1.27 1.27)
				)
				(justify mirror)
			)
		)
		(property "Value" ""
			(at 0 0 90)
			(layer "B.Fab")
			(effects
				(font
					(size 1.27 1.27)
				)
				(justify mirror)
			)
		)
		(duplicate_pad_numbers_are_jumpers no)
		(fp_poly
			(pts
				(xy -0.3048 -0.1016) (xy -0.3048 0.9906) (xy 0.3048 0.9906) (xy 0.3048 -0.1016)
			)
			(stroke
				(width 0)
				(type default)
			)
			(fill no)
			(layer "B.CrtYd")
		)
		(fp_line
			(start 0.3048 -0.1016)
			(end 0.3048 0.9906)
			(stroke
				(width 0.1)
				(type default)
			)
			(layer "B.Fab")
		)
		(fp_line
			(start -0.3048 -0.1016)
			(end 0.3048 -0.1016)
			(stroke
				(width 0.1)
				(type default)
			)
			(layer "B.Fab")
		)
		(fp_line
			(start 0.3048 0.9906)
			(end -0.3048 0.9906)
			(stroke
				(width 0.1)
				(type default)
			)
			(layer "B.Fab")
		)
		(fp_line
			(start -0.3048 0.9906)
			(end -0.3048 -0.1016)
			(stroke
				(width 0.1)
				(type default)
			)
			(layer "B.Fab")
		)
		(pad "1" smd rect
			(at 0 0 270)
			(size 0.508 0.508)
			(layers "B.Cu" "B.Mask" "B.Paste")
			(net "VR_PVCCIO_CPU0_VINSEN")
		)
		(pad "2" smd rect
			(at 0 0.889 270)
			(size 0.508 0.508)
			(layers "B.Cu" "B.Mask" "B.Paste")
			(net "GND")
		)
		(zone
			(layer "B.Cu")
			(hatch none 0.5)
			(connect_pads
				(clearance 0)
			)
			(min_thickness 0.25)
			(keepout
				(tracks allowed)
				(vias not_allowed)
				(pads allowed)
				(copperpour not_allowed)
				(footprints allowed)
			)
			(placement
				(enabled no)
				(sheetname "")
			)
			(fill
				(thermal_gap 0.5)
				(thermal_bridge_width 0.5)
				(island_removal_mode 0)
			)
			(polygon
				(pts
					(xy 351.4852 -86.2076) (xy 351.4852 -85.6996) (xy 351.8662 -85.6996) (xy 351.8662 -86.2076)
				)
			)
		)
		(zone
			(layer "B.Cu")
			(hatch none 0.5)
			(connect_pads
				(clearance 0)
			)
			(min_thickness 0.25)
			(keepout
				(tracks not_allowed)
				(vias allowed)
				(pads allowed)
				(copperpour not_allowed)
				(footprints allowed)
			)
			(placement
				(enabled no)
				(sheetname "")
			)
			(fill
				(thermal_gap 0.5)
				(thermal_bridge_width 0.5)
				(island_removal_mode 0)
			)
			(polygon
				(pts
					(xy 351.8662 -86.2076) (xy 351.8662 -85.6996) (xy 351.4852 -85.6996) (xy 351.4852 -86.2076)
				)
			)
		)
	)
	(footprint ""
		(layer "B.Cu")
		(at 49.5808 -98.1202)
		(property "Reference" "R9N4"
			(at 0 0 0)
			(layer "B.SilkS")
			(hide yes)
			(effects
				(font
					(size 1.27 1.27)
				)
				(justify mirror)
			)
		)
		(property "Value" ""
			(at 0 0 0)
			(layer "B.Fab")
			(effects
				(font
					(size 1.27 1.27)
				)
				(justify mirror)
			)
		)
		(duplicate_pad_numbers_are_jumpers no)
		(fp_poly
			(pts
				(xy 0.2794 -0.1016) (xy -0.2794 -0.1016) (xy -0.2794 0.9906) (xy 0.2794 0.9906)
			)
			(stroke
				(width 0)
				(type default)
			)
			(fill no)
			(layer "B.CrtYd")
		)
		(fp_line
			(start -0.2794 -0.1016)
			(end 0.2794 -0.1016)
			(stroke
				(width 0.1)
				(type default)
			)
			(layer "B.Fab")
		)
		(fp_line
			(start -0.2794 0.9906)
			(end -0.2794 -0.1016)
			(stroke
				(width 0.1)
				(type default)
			)
			(layer "B.Fab")
		)
		(fp_line
			(start 0.2794 -0.1016)
			(end 0.2794 0.9906)
			(stroke
				(width 0.1)
				(type default)
			)
			(layer "B.Fab")
		)
		(fp_line
			(start 0.2794 0.9906)
			(end -0.2794 0.9906)
			(stroke
				(width 0.1)
				(type default)
			)
			(layer "B.Fab")
		)
		(pad "1" smd rect
			(at 0 0 180)
			(size 0.508 0.508)
			(layers "B.Cu" "B.Mask" "B.Paste")
			(net "PVSA_CPU1")
		)
		(pad "2" smd rect
			(at 0 0.889 180)
			(size 0.508 0.508)
			(layers "B.Cu" "B.Mask" "B.Paste")
			(net "GND")
		)
		(zone
			(layer "B.Cu")
			(hatch none 0.5)
			(connect_pads
				(clearance 0)
			)
			(min_thickness 0.25)
			(keepout
				(tracks allowed)
				(vias not_allowed)
				(pads allowed)
				(copperpour not_allowed)
				(footprints allowed)
			)
			(placement
				(enabled no)
				(sheetname "")
			)
			(fill
				(thermal_gap 0.5)
				(thermal_bridge_width 0.5)
				(island_removal_mode 0)
			)
			(polygon
				(pts
					(xy 49.8348 -97.8662) (xy 49.3268 -97.8662) (xy 49.3268 -97.4852) (xy 49.8348 -97.4852)
				)
			)
		)
		(zone
			(layer "B.Cu")
			(hatch none 0.5)
			(connect_pads
				(clearance 0)
			)
			(min_thickness 0.25)
			(keepout
				(tracks not_allowed)
				(vias allowed)
				(pads allowed)
				(copperpour not_allowed)
				(footprints allowed)
			)
			(placement
				(enabled no)
				(sheetname "")
			)
			(fill
				(thermal_gap 0.5)
				(thermal_bridge_width 0.5)
				(island_removal_mode 0)
			)
			(polygon
				(pts
					(xy 49.8348 -97.4852) (xy 49.3268 -97.4852) (xy 49.3268 -97.8662) (xy 49.8348 -97.8662)
				)
			)
		)
	)
	(footprint ""
		(layer "B.Cu")
		(at 167.005 -13.208 90)
		(property "Reference" "C6U3"
			(at 0 0 90)
			(layer "B.SilkS")
			(hide yes)
			(effects
				(font
					(size 1.27 1.27)
				)
				(justify mirror)
			)
		)
		(property "Value" ""
			(at 0 0 90)
			(layer "B.Fab")
			(effects
				(font
					(size 1.27 1.27)
				)
				(justify mirror)
			)
		)
		(duplicate_pad_numbers_are_jumpers no)
		(fp_rect
			(start -0.7239 -0.2159)
			(end 0.7239 1.9939)
			(stroke
				(width 0)
				(type default)
			)
			(fill no)
			(layer "B.CrtYd")
		)
		(fp_line
			(start 0.7239 -0.2159)
			(end 0.7239 1.9939)
			(stroke
				(width 0.1)
				(type default)
			)
			(layer "B.Fab")
		)
		(fp_line
			(start -0.7239 -0.2159)
			(end 0.7239 -0.2159)
			(stroke
				(width 0.1)
				(type default)
			)
			(layer "B.Fab")
		)
		(fp_line
			(start 0.7239 1.9939)
			(end -0.7239 1.9939)
			(stroke
				(width 0.1)
				(type default)
			)
			(layer "B.Fab")
		)
		(fp_line
			(start -0.7239 1.9939)
			(end -0.7239 -0.2159)
			(stroke
				(width 0.1)
				(type default)
			)
			(layer "B.Fab")
		)
		(pad "1" smd rect
			(at 0 0 270)
			(size 1.27 1.016)
			(layers "B.Cu" "B.Mask" "B.Paste")
			(net "PVPP_GHJ")
		)
		(pad "2" smd rect
			(at 0 1.778 270)
			(size 1.27 1.016)
			(layers "B.Cu" "B.Mask" "B.Paste")
			(net "GND")
		)
		(zone
			(layer "B.Cu")
			(hatch none 0.5)
			(connect_pads
				(clearance 0)
			)
			(min_thickness 0.25)
			(keepout
				(tracks not_allowed)
				(vias allowed)
				(pads allowed)
				(copperpour not_allowed)
				(footprints allowed)
			)
			(placement
				(enabled no)
				(sheetname "")
			)
			(fill
				(thermal_gap 0.5)
				(thermal_bridge_width 0.5)
				(island_removal_mode 0)
			)
			(polygon
				(pts
					(xy 167.513 -12.573) (xy 168.275 -12.573) (xy 168.275 -13.843) (xy 167.513 -13.843)
				)
			)
		)
	)
	(footprint ""
		(layer "B.Cu")
		(at 339.3186 -131.6482)
		(property "Reference" "C3M10"
			(at 0 0 0)
			(layer "B.SilkS")
			(hide yes)
			(effects
				(font
					(size 1.27 1.27)
				)
				(justify mirror)
			)
		)
		(property "Value" ""
			(at 0 0 0)
			(layer "B.Fab")
			(effects
				(font
					(size 1.27 1.27)
				)
				(justify mirror)
			)
		)
		(duplicate_pad_numbers_are_jumpers no)
		(fp_poly
			(pts
				(xy 0.4953 -0.2032) (xy -0.4953 -0.2032) (xy -0.4953 1.6002) (xy 0.4953 1.6002)
			)
			(stroke
				(width 0)
				(type default)
			)
			(fill no)
			(layer "B.CrtYd")
		)
		(fp_line
			(start -0.4953 -0.2032)
			(end -0.4953 1.6002)
			(stroke
				(width 0.1)
				(type default)
			)
			(layer "B.Fab")
		)
		(fp_line
			(start -0.4953 1.6002)
			(end 0.4953 1.6002)
			(stroke
				(width 0.1)
				(type default)
			)
			(layer "B.Fab")
		)
		(fp_line
			(start 0.4953 -0.2032)
			(end -0.4953 -0.2032)
			(stroke
				(width 0.1)
				(type default)
			)
			(layer "B.Fab")
		)
		(fp_line
			(start 0.4953 1.6002)
			(end 0.4953 -0.2032)
			(stroke
				(width 0.1)
				(type default)
			)
			(layer "B.Fab")
		)
		(pad "1" smd rect
			(at 0 0 180)
			(size 0.762 0.889)
			(layers "B.Cu" "B.Mask" "B.Paste")
			(net "VR_VB_PVPP_DEF")
		)
		(pad "2" smd rect
			(at 0 1.397 180)
			(size 0.762 0.889)
			(layers "B.Cu" "B.Mask" "B.Paste")
			(net "AGND_PVPP_DEF")
		)
		(zone
			(layer "B.Cu")
			(hatch none 0.5)
			(connect_pads
				(clearance 0)
			)
			(min_thickness 0.25)
			(keepout
				(tracks not_allowed)
				(vias allowed)
				(pads allowed)
				(copperpour not_allowed)
				(footprints allowed)
			)
			(placement
				(enabled no)
				(sheetname "")
			)
			(fill
				(thermal_gap 0.5)
				(thermal_bridge_width 0.5)
				(island_removal_mode 0)
			)
			(polygon
				(pts
					(xy 339.6996 -131.2037) (xy 338.9376 -131.2037) (xy 338.9376 -130.6957) (xy 339.6996 -130.6957)
				)
			)
		)
	)
	(footprint ""
		(layer "B.Cu")
		(at 390.7155 -37.73551 -90)
		(property "Reference" "C2T5"
			(at 0 0 90)
			(layer "B.SilkS")
			(hide yes)
			(effects
				(font
					(size 1.27 1.27)
				)
				(justify mirror)
			)
		)
		(property "Value" ""
			(at 0 0 90)
			(layer "B.Fab")
			(effects
				(font
					(size 1.27 1.27)
				)
				(justify mirror)
			)
		)
		(duplicate_pad_numbers_are_jumpers no)
		(fp_poly
			(pts
				(xy -0.3048 -0.1016) (xy -0.3048 0.9906) (xy 0.3048 0.9906) (xy 0.3048 -0.1016)
			)
			(stroke
				(width 0)
				(type default)
			)
			(fill no)
			(layer "B.CrtYd")
		)
		(fp_line
			(start -0.3048 0.9906)
			(end -0.3048 -0.1016)
			(stroke
				(width 0.1)
				(type default)
			)
			(layer "B.Fab")
		)
		(fp_line
			(start 0.3048 0.9906)
			(end -0.3048 0.9906)
			(stroke
				(width 0.1)
				(type default)
			)
			(layer "B.Fab")
		)
		(fp_line
			(start -0.3048 -0.1016)
			(end 0.3048 -0.1016)
			(stroke
				(width 0.1)
				(type default)
			)
			(layer "B.Fab")
		)
		(fp_line
			(start 0.3048 -0.1016)
			(end 0.3048 0.9906)
			(stroke
				(width 0.1)
				(type default)
			)
			(layer "B.Fab")
		)
		(pad "1" smd rect
			(at 0 0 90)
			(size 0.508 0.508)
			(layers "B.Cu" "B.Mask" "B.Paste")
			(net "P3V3")
		)
		(pad "2" smd rect
			(at 0 0.889 90)
			(size 0.508 0.508)
			(layers "B.Cu" "B.Mask" "B.Paste")
			(net "GND")
		)
		(zone
			(layer "B.Cu")
			(hatch none 0.5)
			(connect_pads
				(clearance 0)
			)
			(min_thickness 0.25)
			(keepout
				(tracks not_allowed)
				(vias allowed)
				(pads allowed)
				(copperpour not_allowed)
				(footprints allowed)
			)
			(placement
				(enabled no)
				(sheetname "")
			)
			(fill
				(thermal_gap 0.5)
				(thermal_bridge_width 0.5)
				(island_removal_mode 0)
			)
			(polygon
				(pts
					(xy 390.0805 -37.48151) (xy 390.0805 -37.98951) (xy 390.4615 -37.98951) (xy 390.4615 -37.48151)
				)
			)
		)
		(zone
			(layer "B.Cu")
			(hatch none 0.5)
			(connect_pads
				(clearance 0)
			)
			(min_thickness 0.25)
			(keepout
				(tracks allowed)
				(vias not_allowed)
				(pads allowed)
				(copperpour not_allowed)
				(footprints allowed)
			)
			(placement
				(enabled no)
				(sheetname "")
			)
			(fill
				(thermal_gap 0.5)
				(thermal_bridge_width 0.5)
				(island_removal_mode 0)
			)
			(polygon
				(pts
					(xy 390.4615 -37.48151) (xy 390.4615 -37.98951) (xy 390.0805 -37.98951) (xy 390.0805 -37.48151)
				)
			)
		)
	)
	(footprint ""
		(layer "B.Cu")
		(at 182.169562 -150.876508)
		(property "Reference" "C6L3"
			(at 0 0 0)
			(layer "B.SilkS")
			(hide yes)
			(effects
				(font
					(size 1.27 1.27)
				)
				(justify mirror)
			)
		)
		(property "Value" ""
			(at 0 0 0)
			(layer "B.Fab")
			(effects
				(font
					(size 1.27 1.27)
				)
				(justify mirror)
			)
		)
		(duplicate_pad_numbers_are_jumpers no)
		(fp_rect
			(start 0.4953 -0.2032)
			(end -0.4953 1.6002)
			(stroke
				(width 0)
				(type default)
			)
			(fill no)
			(layer "B.CrtYd")
		)
		(fp_line
			(start -0.4953 -0.2032)
			(end -0.4953 1.6002)
			(stroke
				(width 0.1)
				(type default)
			)
			(layer "B.Fab")
		)
		(fp_line
			(start -0.4953 1.6002)
			(end 0.4953 1.6002)
			(stroke
				(width 0.1)
				(type default)
			)
			(layer "B.Fab")
		)
		(fp_line
			(start 0.4953 -0.2032)
			(end -0.4953 -0.2032)
			(stroke
				(width 0.1)
				(type default)
			)
			(layer "B.Fab")
		)
		(fp_line
			(start 0.4953 1.6002)
			(end 0.4953 -0.2032)
			(stroke
				(width 0.1)
				(type default)
			)
			(layer "B.Fab")
		)
		(pad "1" smd rect
			(at 0 0 180)
			(size 0.762 0.889)
			(layers "B.Cu" "B.Mask" "B.Paste")
			(net "PVDDQ_DEF")
		)
		(pad "2" smd rect
			(at 0 1.397 180)
			(size 0.762 0.889)
			(layers "B.Cu" "B.Mask" "B.Paste")
			(net "GND")
		)
		(zone
			(layer "B.Cu")
			(hatch none 0.5)
			(connect_pads
				(clearance 0)
			)
			(min_thickness 0.25)
			(keepout
				(tracks not_allowed)
				(vias allowed)
				(pads allowed)
				(copperpour not_allowed)
				(footprints allowed)
			)
			(placement
				(enabled no)
				(sheetname "")
			)
			(fill
				(thermal_gap 0.5)
				(thermal_bridge_width 0.5)
				(island_removal_mode 0)
			)
			(polygon
				(pts
					(xy 182.550562 -150.432008) (xy 181.788562 -150.432008) (xy 181.788562 -149.924008) (xy 182.550562 -149.924008)
				)
			)
		)
	)
	(footprint ""
		(layer "B.Cu")
		(at 420.624 -25.654)
		(property "Reference" "C25W77"
			(at 0.8382 -0.67818 0)
			(unlocked yes)
			(layer "B.SilkS")
			(effects
				(font
					(size 0.4064 0.254)
					(thickness 0.1524)
				)
				(justify left mirror)
			)
		)
		(property "Value" ""
			(at 0 0 0)
			(layer "B.Fab")
			(effects
				(font
					(size 1.27 1.27)
				)
				(justify mirror)
			)
		)
		(duplicate_pad_numbers_are_jumpers no)
		(fp_poly
			(pts
				(xy -0.3048 -0.1016) (xy -0.3048 0.9906) (xy 0.3048 0.9906) (xy 0.3048 -0.1016)
			)
			(stroke
				(width 0)
				(type default)
			)
			(fill no)
			(layer "B.CrtYd")
		)
		(fp_line
			(start -0.3048 -0.1016)
			(end 0.3048 -0.1016)
			(stroke
				(width 0.1)
				(type default)
			)
			(layer "B.Fab")
		)
		(fp_line
			(start -0.3048 0.9906)
			(end -0.3048 -0.1016)
			(stroke
				(width 0.1)
				(type default)
			)
			(layer "B.Fab")
		)
		(fp_line
			(start 0.3048 -0.1016)
			(end 0.3048 0.9906)
			(stroke
				(width 0.1)
				(type default)
			)
			(layer "B.Fab")
		)
		(fp_line
			(start 0.3048 0.9906)
			(end -0.3048 0.9906)
			(stroke
				(width 0.1)
				(type default)
			)
			(layer "B.Fab")
		)
		(pad "1" smd rect
			(at 0 0 180)
			(size 0.508 0.508)
			(layers "B.Cu" "B.Mask" "B.Paste")
			(net "V_IO_R_J")
		)
		(pad "2" smd rect
			(at 0 0.889 180)
			(size 0.508 0.508)
			(layers "B.Cu" "B.Mask" "B.Paste")
			(net "GND")
		)
		(zone
			(layer "B.Cu")
			(hatch none 0.5)
			(connect_pads
				(clearance 0)
			)
			(min_thickness 0.25)
			(keepout
				(tracks allowed)
				(vias not_allowed)
				(pads allowed)
				(copperpour not_allowed)
				(footprints allowed)
			)
			(placement
				(enabled no)
				(sheetname "")
			)
			(fill
				(thermal_gap 0.5)
				(thermal_bridge_width 0.5)
				(island_removal_mode 0)
			)
			(polygon
				(pts
					(xy 420.878 -25.4) (xy 420.37 -25.4) (xy 420.37 -25.019) (xy 420.878 -25.019)
				)
			)
		)
		(zone
			(layer "B.Cu")
			(hatch none 0.5)
			(connect_pads
				(clearance 0)
			)
			(min_thickness 0.25)
			(keepout
				(tracks not_allowed)
				(vias allowed)
				(pads allowed)
				(copperpour not_allowed)
				(footprints allowed)
			)
			(placement
				(enabled no)
				(sheetname "")
			)
			(fill
				(thermal_gap 0.5)
				(thermal_bridge_width 0.5)
				(island_removal_mode 0)
			)
			(polygon
				(pts
					(xy 420.878 -25.019) (xy 420.37 -25.019) (xy 420.37 -25.4) (xy 420.878 -25.4)
				)
			)
		)
	)
)
